(kicad_pcb
	(version 20260206)
	(generator "pcbnew")
	(generator_version "10.0")
	(general
		(thickness 1.6)
		(legacy_teardrops no)
	)
	(paper "A4")
	(title_block
		(title "04192023_DAF0TMB3IC0_F0TG_MB_C_brd_V02_OCP.brd")
		(comment 1 "Grand Teton / footprint 3 of 8354 (J21), pads 114-226 of 291")
	)
	(layers
		(0 "F.Cu" signal "TOP")
		(4 "In1.Cu" signal "GND")
		(6 "In2.Cu" signal "IN1")
		(8 "In3.Cu" signal "GND1")
		(10 "In4.Cu" signal "IN2")
		(12 "In5.Cu" signal "GND2")
		(14 "In6.Cu" signal "IN3")
		(16 "In7.Cu" signal "GND3")
		(18 "In8.Cu" signal "VCC")
		(20 "In9.Cu" signal "VCC1")
		(22 "In10.Cu" signal "GND4")
		(24 "In11.Cu" signal "IN4")
		(26 "In12.Cu" signal "GND5")
		(28 "In13.Cu" signal "IN5")
		(30 "In14.Cu" signal "GND6")
		(32 "In15.Cu" signal "IN6")
		(34 "In16.Cu" signal "GND7")
		(2 "B.Cu" signal "BOTTOM")
		(9 "F.Adhes" user "F.Adhesive")
		(11 "B.Adhes" user "B.Adhesive")
		(13 "F.Paste" user "Package Geometry/Pastemask Top")
		(15 "B.Paste" user "Package Geometry/Pastemask Bottom")
		(5 "F.SilkS" user "Ref Des/Silkscreen Top")
		(7 "B.SilkS" user "Ref Des/Silkscreen Bottom")
		(1 "F.Mask" user "Board Geometry/Soldermask Top")
		(3 "B.Mask" user "Board Geometry/Soldermask Bottom")
		(17 "Dwgs.User" user "User.Drawings")
		(19 "Cmts.User" user "User.Comments")
		(21 "Eco1.User" user "User.Eco1")
		(23 "Eco2.User" user "User.Eco2")
		(25 "Edge.Cuts" user "Board Geometry/Outline")
		(27 "Margin" user)
		(31 "F.CrtYd" user "Package Geometry/Place Bound Top")
		(29 "B.CrtYd" user "Package Geometry/Place Bound Bottom")
		(35 "F.Fab" user "Ref Des/Assembly Top")
		(33 "B.Fab" user "Ref Des/Assembly Bottom")
	)
	(footprint ""
		(layer "F.Cu")
		(at 275.142198 -255.560068 180)
		(property "Reference" "J21"
			(at -2.2098 -81.984088 0)
			(unlocked yes)
			(layer "F.SilkS")
			(effects
				(font
					(size 0.7874 0.5842)
					(thickness 0.1524)
				)
			)
		)
		(property "Value" ""
			(at 0 0 180)
			(layer "F.Fab")
			(effects
				(font
					(size 1.27 1.27)
				)
			)
		)
		(duplicate_pad_numbers_are_jumpers no)
		(pad "114" smd rect
			(at -2.050034 37.824918 90)
			(size 0.519938 1.4986)
			(layers "F.Cu" "F.Mask" "F.Paste")
			(net "GND")
		)
		(pad "115" smd rect
			(at -2.050034 38.675056 90)
			(size 0.519938 1.4986)
			(layers "F.Cu" "F.Mask" "F.Paste")
			(net "M_E_CPU0_SB_DQS_DP<1>")
		)
		(pad "116" smd rect
			(at -2.050034 39.52494 90)
			(size 0.519938 1.4986)
			(layers "F.Cu" "F.Mask" "F.Paste")
			(net "M_E_CPU0_SB_DQS_DN<1>")
		)
		(pad "117" smd rect
			(at -2.050034 40.375078 90)
			(size 0.519938 1.4986)
			(layers "F.Cu" "F.Mask" "F.Paste")
			(net "GND")
		)
		(pad "118" smd rect
			(at -2.050034 41.224962 90)
			(size 0.519938 1.4986)
			(layers "F.Cu" "F.Mask" "F.Paste")
			(net "M_E_CPU0_SB_DQ<12>")
		)
		(pad "119" smd rect
			(at -2.050034 42.0751 90)
			(size 0.519938 1.4986)
			(layers "F.Cu" "F.Mask" "F.Paste")
			(net "GND")
		)
		(pad "120" smd rect
			(at -2.050034 42.924984 90)
			(size 0.519938 1.4986)
			(layers "F.Cu" "F.Mask" "F.Paste")
			(net "M_E_CPU0_SB_DQ<13>")
		)
		(pad "121" smd rect
			(at -2.050034 43.775122 90)
			(size 0.519938 1.4986)
			(layers "F.Cu" "F.Mask" "F.Paste")
			(net "GND")
		)
		(pad "122" smd rect
			(at -2.050034 44.625006 90)
			(size 0.519938 1.4986)
			(layers "F.Cu" "F.Mask" "F.Paste")
			(net "M_E_CPU0_SB_DQ<16>")
		)
		(pad "123" smd rect
			(at -2.050034 45.47489 90)
			(size 0.519938 1.4986)
			(layers "F.Cu" "F.Mask" "F.Paste")
			(net "GND")
		)
		(pad "124" smd rect
			(at -2.050034 46.325028 90)
			(size 0.519938 1.4986)
			(layers "F.Cu" "F.Mask" "F.Paste")
			(net "M_E_CPU0_SB_DQ<17>")
		)
		(pad "125" smd rect
			(at -2.050034 47.174912 90)
			(size 0.519938 1.4986)
			(layers "F.Cu" "F.Mask" "F.Paste")
			(net "GND")
		)
		(pad "126" smd rect
			(at -2.050034 48.02505 90)
			(size 0.519938 1.4986)
			(layers "F.Cu" "F.Mask" "F.Paste")
			(net "M_E_CPU0_SB_DQS_DP<2>")
		)
		(pad "127" smd rect
			(at -2.050034 48.874934 90)
			(size 0.519938 1.4986)
			(layers "F.Cu" "F.Mask" "F.Paste")
			(net "M_E_CPU0_SB_DQS_DN<2>")
		)
		(pad "128" smd rect
			(at -2.050034 49.725072 90)
			(size 0.519938 1.4986)
			(layers "F.Cu" "F.Mask" "F.Paste")
			(net "GND")
		)
		(pad "129" smd rect
			(at -2.050034 50.574956 90)
			(size 0.519938 1.4986)
			(layers "F.Cu" "F.Mask" "F.Paste")
			(net "M_E_CPU0_SB_DQ<20>")
		)
		(pad "130" smd rect
			(at -2.050034 51.425094 90)
			(size 0.519938 1.4986)
			(layers "F.Cu" "F.Mask" "F.Paste")
			(net "GND")
		)
		(pad "131" smd rect
			(at -2.050034 52.274978 90)
			(size 0.519938 1.4986)
			(layers "F.Cu" "F.Mask" "F.Paste")
			(net "M_E_CPU0_SB_DQ<21>")
		)
		(pad "132" smd rect
			(at -2.050034 53.125116 90)
			(size 0.519938 1.4986)
			(layers "F.Cu" "F.Mask" "F.Paste")
			(net "GND")
		)
		(pad "133" smd rect
			(at -2.050034 53.975 90)
			(size 0.519938 1.4986)
			(layers "F.Cu" "F.Mask" "F.Paste")
			(net "M_E_CPU0_SB_DQ<24>")
		)
		(pad "134" smd rect
			(at -2.050034 54.824884 90)
			(size 0.519938 1.4986)
			(layers "F.Cu" "F.Mask" "F.Paste")
			(net "GND")
		)
		(pad "135" smd rect
			(at -2.050034 55.675022 90)
			(size 0.519938 1.4986)
			(layers "F.Cu" "F.Mask" "F.Paste")
			(net "M_E_CPU0_SB_DQ<25>")
		)
		(pad "136" smd rect
			(at -2.050034 56.524906 90)
			(size 0.519938 1.4986)
			(layers "F.Cu" "F.Mask" "F.Paste")
			(net "GND")
		)
		(pad "137" smd rect
			(at -2.050034 57.375044 90)
			(size 0.519938 1.4986)
			(layers "F.Cu" "F.Mask" "F.Paste")
			(net "M_E_CPU0_SB_DQS_DP<3>")
		)
		(pad "138" smd rect
			(at -2.050034 58.224928 90)
			(size 0.519938 1.4986)
			(layers "F.Cu" "F.Mask" "F.Paste")
			(net "M_E_CPU0_SB_DQS_DN<3>")
		)
		(pad "139" smd rect
			(at -2.050034 59.075066 90)
			(size 0.519938 1.4986)
			(layers "F.Cu" "F.Mask" "F.Paste")
			(net "GND")
		)
		(pad "140" smd rect
			(at -2.050034 59.92495 90)
			(size 0.519938 1.4986)
			(layers "F.Cu" "F.Mask" "F.Paste")
			(net "M_E_CPU0_SB_DQ<28>")
		)
		(pad "141" smd rect
			(at -2.050034 60.775088 90)
			(size 0.519938 1.4986)
			(layers "F.Cu" "F.Mask" "F.Paste")
			(net "GND")
		)
		(pad "142" smd rect
			(at -2.050034 61.624972 90)
			(size 0.519938 1.4986)
			(layers "F.Cu" "F.Mask" "F.Paste")
			(net "M_E_CPU0_SB_DQ<29>")
		)
		(pad "143" smd rect
			(at -2.050034 62.47511 90)
			(size 0.519938 1.4986)
			(layers "F.Cu" "F.Mask" "F.Paste")
			(net "GND")
		)
		(pad "144" smd rect
			(at -2.050034 63.324994 90)
			(size 0.519938 1.4986)
			(layers "F.Cu" "F.Mask" "F.Paste")
			(net "Net_2306")
		)
		(pad "145" smd rect
			(at 2.050034 -63.324994 90)
			(size 0.519938 1.4986)
			(layers "F.Cu" "F.Mask" "F.Paste")
			(net "P12V_MEM_CPU0")
		)
		(pad "146" smd rect
			(at 2.050034 -62.47511 90)
			(size 0.519938 1.4986)
			(layers "F.Cu" "F.Mask" "F.Paste")
			(net "P12V_MEM_CPU0")
		)
		(pad "147" smd rect
			(at 2.050034 -61.624972 90)
			(size 0.519938 1.4986)
			(layers "F.Cu" "F.Mask" "F.Paste")
			(net "PWRGD_CHE_CPU0_DIMM")
		)
		(pad "148" smd rect
			(at 2.050034 -60.775088 90)
			(size 0.519938 1.4986)
			(layers "F.Cu" "F.Mask" "F.Paste")
			(net "PD_CHE_CPU0_DIMM_SAA")
		)
		(pad "149" smd rect
			(at 2.050034 -59.92495 90)
			(size 0.519938 1.4986)
			(layers "F.Cu" "F.Mask" "F.Paste")
			(net "Net_2307")
		)
		(pad "150" smd rect
			(at 2.050034 -59.075066 90)
			(size 0.519938 1.4986)
			(layers "F.Cu" "F.Mask" "F.Paste")
			(net "Net_2308")
		)
		(pad "151" smd rect
			(at 2.050034 -58.224928 90)
			(size 0.519938 1.4986)
			(layers "F.Cu" "F.Mask" "F.Paste")
			(net "GND")
		)
		(pad "152" smd rect
			(at 2.050034 -57.375044 90)
			(size 0.519938 1.4986)
			(layers "F.Cu" "F.Mask" "F.Paste")
			(net "M_E_CPU0_SA_DQ<2>")
		)
		(pad "153" smd rect
			(at 2.050034 -56.524906 90)
			(size 0.519938 1.4986)
			(layers "F.Cu" "F.Mask" "F.Paste")
			(net "GND")
		)
		(pad "154" smd rect
			(at 2.050034 -55.675022 90)
			(size 0.519938 1.4986)
			(layers "F.Cu" "F.Mask" "F.Paste")
			(net "M_E_CPU0_SA_DQ<3>")
		)
		(pad "155" smd rect
			(at 2.050034 -54.824884 90)
			(size 0.519938 1.4986)
			(layers "F.Cu" "F.Mask" "F.Paste")
			(net "GND")
		)
		(pad "156" smd rect
			(at 2.050034 -53.975 90)
			(size 0.519938 1.4986)
			(layers "F.Cu" "F.Mask" "F.Paste")
			(net "M_E_CPU0_SA_DQS_DN<5>")
		)
		(pad "157" smd rect
			(at 2.050034 -53.125116 90)
			(size 0.519938 1.4986)
			(layers "F.Cu" "F.Mask" "F.Paste")
			(net "M_E_CPU0_SA_DQS_DP<5>")
		)
		(pad "158" smd rect
			(at 2.050034 -52.274978 90)
			(size 0.519938 1.4986)
			(layers "F.Cu" "F.Mask" "F.Paste")
			(net "GND")
		)
		(pad "159" smd rect
			(at 2.050034 -51.425094 90)
			(size 0.519938 1.4986)
			(layers "F.Cu" "F.Mask" "F.Paste")
			(net "M_E_CPU0_SA_DQ<6>")
		)
		(pad "160" smd rect
			(at 2.050034 -50.574956 90)
			(size 0.519938 1.4986)
			(layers "F.Cu" "F.Mask" "F.Paste")
			(net "GND")
		)
		(pad "161" smd rect
			(at 2.050034 -49.725072 90)
			(size 0.519938 1.4986)
			(layers "F.Cu" "F.Mask" "F.Paste")
			(net "M_E_CPU0_SA_DQ<7>")
		)
		(pad "162" smd rect
			(at 2.050034 -48.874934 90)
			(size 0.519938 1.4986)
			(layers "F.Cu" "F.Mask" "F.Paste")
			(net "GND")
		)
		(pad "163" smd rect
			(at 2.050034 -48.02505 90)
			(size 0.519938 1.4986)
			(layers "F.Cu" "F.Mask" "F.Paste")
			(net "M_E_CPU0_SA_DQ<10>")
		)
		(pad "164" smd rect
			(at 2.050034 -47.174912 90)
			(size 0.519938 1.4986)
			(layers "F.Cu" "F.Mask" "F.Paste")
			(net "GND")
		)
		(pad "165" smd rect
			(at 2.050034 -46.325028 90)
			(size 0.519938 1.4986)
			(layers "F.Cu" "F.Mask" "F.Paste")
			(net "M_E_CPU0_SA_DQ<11>")
		)
		(pad "166" smd rect
			(at 2.050034 -45.47489 90)
			(size 0.519938 1.4986)
			(layers "F.Cu" "F.Mask" "F.Paste")
			(net "GND")
		)
		(pad "167" smd rect
			(at 2.050034 -44.625006 90)
			(size 0.519938 1.4986)
			(layers "F.Cu" "F.Mask" "F.Paste")
			(net "M_E_CPU0_SA_DQS_DN<6>")
		)
		(pad "168" smd rect
			(at 2.050034 -43.775122 90)
			(size 0.519938 1.4986)
			(layers "F.Cu" "F.Mask" "F.Paste")
			(net "M_E_CPU0_SA_DQS_DP<6>")
		)
		(pad "169" smd rect
			(at 2.050034 -42.924984 90)
			(size 0.519938 1.4986)
			(layers "F.Cu" "F.Mask" "F.Paste")
			(net "GND")
		)
		(pad "170" smd rect
			(at 2.050034 -42.0751 90)
			(size 0.519938 1.4986)
			(layers "F.Cu" "F.Mask" "F.Paste")
			(net "M_E_CPU0_SA_DQ<14>")
		)
		(pad "171" smd rect
			(at 2.050034 -41.224962 90)
			(size 0.519938 1.4986)
			(layers "F.Cu" "F.Mask" "F.Paste")
			(net "GND")
		)
		(pad "172" smd rect
			(at 2.050034 -40.375078 90)
			(size 0.519938 1.4986)
			(layers "F.Cu" "F.Mask" "F.Paste")
			(net "M_E_CPU0_SA_DQ<15>")
		)
		(pad "173" smd rect
			(at 2.050034 -39.52494 90)
			(size 0.519938 1.4986)
			(layers "F.Cu" "F.Mask" "F.Paste")
			(net "GND")
		)
		(pad "174" smd rect
			(at 2.050034 -38.675056 90)
			(size 0.519938 1.4986)
			(layers "F.Cu" "F.Mask" "F.Paste")
			(net "M_E_CPU0_SA_DQ<18>")
		)
		(pad "175" smd rect
			(at 2.050034 -37.824918 90)
			(size 0.519938 1.4986)
			(layers "F.Cu" "F.Mask" "F.Paste")
			(net "GND")
		)
		(pad "176" smd rect
			(at 2.050034 -36.975034 90)
			(size 0.519938 1.4986)
			(layers "F.Cu" "F.Mask" "F.Paste")
			(net "M_E_CPU0_SA_DQ<19>")
		)
		(pad "177" smd rect
			(at 2.050034 -36.124896 90)
			(size 0.519938 1.4986)
			(layers "F.Cu" "F.Mask" "F.Paste")
			(net "GND")
		)
		(pad "178" smd rect
			(at 2.050034 -35.275012 90)
			(size 0.519938 1.4986)
			(layers "F.Cu" "F.Mask" "F.Paste")
			(net "M_E_CPU0_SA_DQS_DN<7>")
		)
		(pad "179" smd rect
			(at 2.050034 -34.425128 90)
			(size 0.519938 1.4986)
			(layers "F.Cu" "F.Mask" "F.Paste")
			(net "M_E_CPU0_SA_DQS_DP<7>")
		)
		(pad "180" smd rect
			(at 2.050034 -33.57499 90)
			(size 0.519938 1.4986)
			(layers "F.Cu" "F.Mask" "F.Paste")
			(net "GND")
		)
		(pad "181" smd rect
			(at 2.050034 -32.725106 90)
			(size 0.519938 1.4986)
			(layers "F.Cu" "F.Mask" "F.Paste")
			(net "M_E_CPU0_SA_DQ<22>")
		)
		(pad "182" smd rect
			(at 2.050034 -31.874968 90)
			(size 0.519938 1.4986)
			(layers "F.Cu" "F.Mask" "F.Paste")
			(net "GND")
		)
		(pad "183" smd rect
			(at 2.050034 -31.025084 90)
			(size 0.519938 1.4986)
			(layers "F.Cu" "F.Mask" "F.Paste")
			(net "M_E_CPU0_SA_DQ<23>")
		)
		(pad "184" smd rect
			(at 2.050034 -30.174946 90)
			(size 0.519938 1.4986)
			(layers "F.Cu" "F.Mask" "F.Paste")
			(net "GND")
		)
		(pad "185" smd rect
			(at 2.050034 -29.325062 90)
			(size 0.519938 1.4986)
			(layers "F.Cu" "F.Mask" "F.Paste")
			(net "M_E_CPU0_SA_DQ<26>")
		)
		(pad "186" smd rect
			(at 2.050034 -28.474924 90)
			(size 0.519938 1.4986)
			(layers "F.Cu" "F.Mask" "F.Paste")
			(net "GND")
		)
		(pad "187" smd rect
			(at 2.050034 -27.62504 90)
			(size 0.519938 1.4986)
			(layers "F.Cu" "F.Mask" "F.Paste")
			(net "M_E_CPU0_SA_DQ<27>")
		)
		(pad "188" smd rect
			(at 2.050034 -26.774902 90)
			(size 0.519938 1.4986)
			(layers "F.Cu" "F.Mask" "F.Paste")
			(net "GND")
		)
		(pad "189" smd rect
			(at 2.050034 -25.925018 90)
			(size 0.519938 1.4986)
			(layers "F.Cu" "F.Mask" "F.Paste")
			(net "M_E_CPU0_SA_DQS_DN<8>")
		)
		(pad "190" smd rect
			(at 2.050034 -25.07488 90)
			(size 0.519938 1.4986)
			(layers "F.Cu" "F.Mask" "F.Paste")
			(net "M_E_CPU0_SA_DQS_DP<8>")
		)
		(pad "191" smd rect
			(at 2.050034 -24.224996 90)
			(size 0.519938 1.4986)
			(layers "F.Cu" "F.Mask" "F.Paste")
			(net "GND")
		)
		(pad "192" smd rect
			(at 2.050034 -23.375112 90)
			(size 0.519938 1.4986)
			(layers "F.Cu" "F.Mask" "F.Paste")
			(net "M_E_CPU0_SA_DQ<30>")
		)
		(pad "193" smd rect
			(at 2.050034 -22.524974 90)
			(size 0.519938 1.4986)
			(layers "F.Cu" "F.Mask" "F.Paste")
			(net "GND")
		)
		(pad "194" smd rect
			(at 2.050034 -21.67509 90)
			(size 0.519938 1.4986)
			(layers "F.Cu" "F.Mask" "F.Paste")
			(net "M_E_CPU0_SA_DQ<31>")
		)
		(pad "195" smd rect
			(at 2.050034 -20.824952 90)
			(size 0.519938 1.4986)
			(layers "F.Cu" "F.Mask" "F.Paste")
			(net "GND")
		)
		(pad "196" smd rect
			(at 2.050034 -19.975068 90)
			(size 0.519938 1.4986)
			(layers "F.Cu" "F.Mask" "F.Paste")
			(net "M_E_CPU0_SA_CB<2>")
		)
		(pad "197" smd rect
			(at 2.050034 -19.12493 90)
			(size 0.519938 1.4986)
			(layers "F.Cu" "F.Mask" "F.Paste")
			(net "GND")
		)
		(pad "198" smd rect
			(at 2.050034 -18.275046 90)
			(size 0.519938 1.4986)
			(layers "F.Cu" "F.Mask" "F.Paste")
			(net "M_E_CPU0_SA_CB<3>")
		)
		(pad "199" smd rect
			(at 2.050034 -17.424908 90)
			(size 0.519938 1.4986)
			(layers "F.Cu" "F.Mask" "F.Paste")
			(net "GND")
		)
		(pad "200" smd rect
			(at 2.050034 -16.575024 90)
			(size 0.519938 1.4986)
			(layers "F.Cu" "F.Mask" "F.Paste")
			(net "M_E_CPU0_SA_DQS_DN<9>")
		)
		(pad "201" smd rect
			(at 2.050034 -15.724886 90)
			(size 0.519938 1.4986)
			(layers "F.Cu" "F.Mask" "F.Paste")
			(net "M_E_CPU0_SA_DQS_DP<9>")
		)
		(pad "202" smd rect
			(at 2.050034 -14.875002 90)
			(size 0.519938 1.4986)
			(layers "F.Cu" "F.Mask" "F.Paste")
			(net "GND")
		)
		(pad "203" smd rect
			(at 2.050034 -14.025118 90)
			(size 0.519938 1.4986)
			(layers "F.Cu" "F.Mask" "F.Paste")
			(net "M_E_CPU0_SA_CB<6>")
		)
		(pad "204" smd rect
			(at 2.050034 -13.17498 90)
			(size 0.519938 1.4986)
			(layers "F.Cu" "F.Mask" "F.Paste")
			(net "GND")
		)
		(pad "205" smd rect
			(at 2.050034 -12.325096 90)
			(size 0.519938 1.4986)
			(layers "F.Cu" "F.Mask" "F.Paste")
			(net "M_E_CPU0_SA_CB<7>")
		)
		(pad "206" smd rect
			(at 2.050034 -11.474958 90)
			(size 0.519938 1.4986)
			(layers "F.Cu" "F.Mask" "F.Paste")
			(net "GND")
		)
		(pad "207" smd rect
			(at 2.050034 -10.625074 90)
			(size 0.519938 1.4986)
			(layers "F.Cu" "F.Mask" "F.Paste")
			(net "M_E_CPU0_RESET_N")
		)
		(pad "208" smd rect
			(at 2.050034 -9.774936 90)
			(size 0.519938 1.4986)
			(layers "F.Cu" "F.Mask" "F.Paste")
			(net "GND")
		)
		(pad "209" smd rect
			(at 2.050034 -8.925052 90)
			(size 0.519938 1.4986)
			(layers "F.Cu" "F.Mask" "F.Paste")
			(net "M_E_CPU0_SA_CS_N<1>")
		)
		(pad "210" smd rect
			(at 2.050034 -8.074914 90)
			(size 0.519938 1.4986)
			(layers "F.Cu" "F.Mask" "F.Paste")
			(net "GND")
		)
		(pad "211" smd rect
			(at 2.050034 -7.22503 90)
			(size 0.519938 1.4986)
			(layers "F.Cu" "F.Mask" "F.Paste")
			(net "M_E_CPU0_SA_CA<1>")
		)
		(pad "212" smd rect
			(at 2.050034 -6.374892 90)
			(size 0.519938 1.4986)
			(layers "F.Cu" "F.Mask" "F.Paste")
			(net "GND")
		)
		(pad "213" smd rect
			(at 2.050034 -5.525008 90)
			(size 0.519938 1.4986)
			(layers "F.Cu" "F.Mask" "F.Paste")
			(net "M_E_CPU0_SA_CA<3>")
		)
		(pad "214" smd rect
			(at 2.050034 -4.675124 90)
			(size 0.519938 1.4986)
			(layers "F.Cu" "F.Mask" "F.Paste")
			(net "GND")
		)
		(pad "215" smd rect
			(at 2.050034 -3.824986 90)
			(size 0.519938 1.4986)
			(layers "F.Cu" "F.Mask" "F.Paste")
			(net "M_E_CPU0_SA_CA<5>")
		)
		(pad "216" smd rect
			(at 2.050034 -2.975102 90)
			(size 0.519938 1.4986)
			(layers "F.Cu" "F.Mask" "F.Paste")
			(net "GND")
		)
		(pad "217" smd rect
			(at 2.050034 -2.124964 90)
			(size 0.519938 1.4986)
			(layers "F.Cu" "F.Mask" "F.Paste")
			(net "M_E_CPU0_CLK_DP<0>")
		)
		(pad "218" smd rect
			(at 2.050034 -1.27508 90)
			(size 0.519938 1.4986)
			(layers "F.Cu" "F.Mask" "F.Paste")
			(net "M_E_CPU0_CLK_DN<0>")
		)
		(pad "219" smd rect
			(at 2.050034 -0.424942 90)
			(size 0.519938 1.4986)
			(layers "F.Cu" "F.Mask" "F.Paste")
			(net "GND")
		)
		(pad "220" smd rect
			(at 2.050034 5.525008 90)
			(size 0.519938 1.4986)
			(layers "F.Cu" "F.Mask" "F.Paste")
			(net "Net_2309")
		)
		(pad "221" smd rect
			(at 2.050034 6.374892 90)
			(size 0.519938 1.4986)
			(layers "F.Cu" "F.Mask" "F.Paste")
			(net "M_E_CPU0_SB_CA<1>")
		)
		(pad "222" smd rect
			(at 2.050034 7.22503 90)
			(size 0.519938 1.4986)
			(layers "F.Cu" "F.Mask" "F.Paste")
			(net "GND")
		)
		(pad "223" smd rect
			(at 2.050034 8.074914 90)
			(size 0.519938 1.4986)
			(layers "F.Cu" "F.Mask" "F.Paste")
			(net "M_E_CPU0_SB_CA<3>")
		)
		(pad "224" smd rect
			(at 2.050034 8.925052 90)
			(size 0.519938 1.4986)
			(layers "F.Cu" "F.Mask" "F.Paste")
			(net "GND")
		)
		(pad "225" smd rect
			(at 2.050034 9.774936 90)
			(size 0.519938 1.4986)
			(layers "F.Cu" "F.Mask" "F.Paste")
			(net "M_E_CPU0_SB_CA<5>")
		)
		(pad "226" smd rect
			(at 2.050034 10.625074 90)
			(size 0.519938 1.4986)
			(layers "F.Cu" "F.Mask" "F.Paste")
			(net "GND")
		)
	)
)
